G04 #@! TF.GenerationSoftware,KiCad,Pcbnew,(5.0.1)-3*
G04 #@! TF.CreationDate,2019-04-10T15:36:06+02:00*
G04 #@! TF.ProjectId,discovery,646973636F766572792E6B696361645F,rev?*
G04 #@! TF.SameCoordinates,PX4c4640PY8a48028*
G04 #@! TF.FileFunction,Profile,NP*
%FSLAX46Y46*%
G04 Gerber Fmt 4.6, Leading zero omitted, Abs format (unit mm)*
%MOMM*%
%LPD*%
G01*
G04 APERTURE LIST*
%ADD10C,0.150000*%
G04 APERTURE END LIST*
D10*
X143001280Y-5001560D02*
X145001280Y-3001560D01*
X143001280Y94998440D02*
X145001280Y92998440D01*
X-4998720Y92998440D02*
X-2998720Y94998440D01*
X-4998720Y-3001560D02*
X-2998720Y-5001560D01*
X-2998720Y94998440D02*
X143001280Y94998440D01*
X-4998720Y-3001560D02*
X-4998720Y92998440D01*
X-2998720Y-5001560D02*
X143001280Y-5001560D01*
X145001280Y92998440D02*
X145001280Y-3001560D01*
M02*
